# S9S_MB_2U (Grand Teton) — schematic netlist excerpt (pin names and nets, part order shuffled) for the footprints in the layout excerpt that follows; sources: Cadence DE-HDL packaged netlist, KiCad conversion of 03242023_DA0F0TMBIJ0_F0T_Motherboard_J_brd_V01_OCP.brd

DB2  TDR_3P  EMPTY  pkg TH2  page 309
  GND  = T1_GND
  IO1  = TDR_SE_40_OHM_IN1
  IO2  = TDR_SE_40_OHM_IN1

R2521  Q_RES  0 5% CHIP  pkg 0402LF  page 284 : A = SMB_VR_3V3AUX_SDA_R3 ; B = SMB_DIO_PVCCIN_CPU1
R3834  Q_RES  0 5% CHIP  pkg 0402LF  page 157 : A = HP_LVC3_OCP_V3_1_EN ; B = P12V_OCP_EN_1_R2

(kicad_pcb
	(version 20260206)
	(generator "pcbnew")
	(generator_version "10.0")
	(general
		(thickness 1.6)
		(legacy_teardrops no)
	)
	(paper "A4")
	(title_block
		(title "03242023_DA0F0TMBIJ0_F0T_Motherboard_J_brd_V01_OCP.brd")
		(comment 1 "Grand Teton / footprints 534-536 of 6105")
	)
	(layers
		(0 "F.Cu" signal "TOP")
		(4 "In1.Cu" signal "GND")
		(6 "In2.Cu" signal "IN1")
		(8 "In3.Cu" signal "GND1")
		(10 "In4.Cu" signal "IN2")
		(12 "In5.Cu" signal "GND2")
		(14 "In6.Cu" signal "IN3")
		(16 "In7.Cu" signal "GND3")
		(18 "In8.Cu" signal "VCC")
		(20 "In9.Cu" signal "VCC1")
		(22 "In10.Cu" signal "GND4")
		(24 "In11.Cu" signal "IN4")
		(26 "In12.Cu" signal "GND5")
		(28 "In13.Cu" signal "IN5")
		(30 "In14.Cu" signal "GND6")
		(32 "In15.Cu" signal "IN6")
		(34 "In16.Cu" signal "GND7")
		(2 "B.Cu" signal "BOTTOM")
		(9 "F.Adhes" user "F.Adhesive")
		(11 "B.Adhes" user "B.Adhesive")
		(13 "F.Paste" user "Package Geometry/Pastemask Top")
		(15 "B.Paste" user "Package Geometry/Pastemask Bottom")
		(5 "F.SilkS" user "Ref Des/Silkscreen Top")
		(7 "B.SilkS" user "Ref Des/Silkscreen Bottom")
		(1 "F.Mask" user "Board Geometry/Soldermask Top")
		(3 "B.Mask" user "Board Geometry/Soldermask Bottom")
		(17 "Dwgs.User" user "User.Drawings")
		(19 "Cmts.User" user "User.Comments")
		(21 "Eco1.User" user "User.Eco1")
		(23 "Eco2.User" user "User.Eco2")
		(25 "Edge.Cuts" user "Board Geometry/Outline")
		(27 "Margin" user)
		(31 "F.CrtYd" user "Package Geometry/Place Bound Top")
		(29 "B.CrtYd" user "Package Geometry/Place Bound Bottom")
		(35 "F.Fab" user "Ref Des/Assembly Top")
		(33 "B.Fab" user "Ref Des/Assembly Bottom")
	)
	(footprint ""
		(layer "F.Cu")
		(at 444.733172 -32.173418 -90)
		(property "Reference" "R3834"
			(at 0 0 270)
			(layer "F.SilkS")
			(hide yes)
			(effects
				(font
					(size 1.27 1.27)
				)
			)
		)
		(property "Value" ""
			(at 0 0 270)
			(layer "F.Fab")
			(effects
				(font
					(size 1.27 1.27)
				)
			)
		)
		(duplicate_pad_numbers_are_jumpers no)
		(fp_line
			(start -0.7874 0.4064)
			(end -0.7874 -0.4064)
			(stroke
				(width 0.1524)
				(type default)
			)
			(layer "F.SilkS")
		)
		(fp_line
			(start 0.7874 0.4064)
			(end -0.7874 0.4064)
			(stroke
				(width 0.1524)
				(type default)
			)
			(layer "F.SilkS")
		)
		(fp_line
			(start -0.7874 -0.4064)
			(end 0.7874 -0.4064)
			(stroke
				(width 0.1524)
				(type default)
			)
			(layer "F.SilkS")
		)
		(fp_line
			(start 0.7874 -0.4064)
			(end 0.7874 0.4064)
			(stroke
				(width 0.1524)
				(type default)
			)
			(layer "F.SilkS")
		)
		(fp_line
			(start -0.67945 0.3048)
			(end -0.67945 -0.305054)
			(stroke
				(width 0.1)
				(type default)
			)
			(layer "F.Fab")
		)
		(fp_line
			(start -0.12065 0.3048)
			(end -0.67945 0.3048)
			(stroke
				(width 0.1)
				(type default)
			)
			(layer "F.Fab")
		)
		(fp_line
			(start 0.120396 0.3048)
			(end 0.120396 0.2794)
			(stroke
				(width 0.1)
				(type default)
			)
			(layer "F.Fab")
		)
		(fp_line
			(start 0.67945 0.3048)
			(end 0.120396 0.3048)
			(stroke
				(width 0.1)
				(type default)
			)
			(layer "F.Fab")
		)
		(fp_line
			(start -0.12065 0.2794)
			(end -0.12065 0.3048)
			(stroke
				(width 0.1)
				(type default)
			)
			(layer "F.Fab")
		)
		(fp_line
			(start 0.120396 0.2794)
			(end -0.12065 0.2794)
			(stroke
				(width 0.1)
				(type default)
			)
			(layer "F.Fab")
		)
		(fp_line
			(start -0.12065 -0.2794)
			(end 0.12065 -0.2794)
			(stroke
				(width 0.1)
				(type default)
			)
			(layer "F.Fab")
		)
		(fp_line
			(start 0.12065 -0.2794)
			(end 0.12065 -0.3048)
			(stroke
				(width 0.1)
				(type default)
			)
			(layer "F.Fab")
		)
		(fp_line
			(start 0.12065 -0.3048)
			(end 0.67945 -0.3048)
			(stroke
				(width 0.1)
				(type default)
			)
			(layer "F.Fab")
		)
		(fp_line
			(start 0.67945 -0.3048)
			(end 0.67945 0.3048)
			(stroke
				(width 0.1)
				(type default)
			)
			(layer "F.Fab")
		)
		(fp_line
			(start -0.67945 -0.305054)
			(end -0.12065 -0.305054)
			(stroke
				(width 0.1)
				(type default)
			)
			(layer "F.Fab")
		)
		(fp_line
			(start -0.12065 -0.305054)
			(end -0.12065 -0.2794)
			(stroke
				(width 0.1)
				(type default)
			)
			(layer "F.Fab")
		)
		(pad "1" smd circle
			(at -0.40005 0 270)
			(size 0 0)
			(layers "F.Cu" "F.Mask" "F.Paste")
			(net "HP_LVC3_OCP_V3_1_EN")
		)
		(pad "2" smd circle
			(at 0.40005 0 270)
			(size 0 0)
			(layers "F.Cu" "F.Mask" "F.Paste")
			(net "P12V_OCP_EN_1_R2")
		)
	)
	(footprint ""
		(layer "F.Cu")
		(at 506.378972 -342.873838)
		(property "Reference" "DB2"
			(at 2.71399 1.386586 90)
			(unlocked yes)
			(layer "F.SilkS")
			(effects
				(font
					(size 0.7874 0.5842)
					(thickness 0.1524)
				)
				(justify left)
			)
		)
		(property "Value" ""
			(at 0 0 0)
			(layer "F.Fab")
			(effects
				(font
					(size 1.27 1.27)
				)
			)
		)
		(duplicate_pad_numbers_are_jumpers no)
		(fp_line
			(start -3.330702 -4.771136)
			(end 3.330702 -4.771136)
			(stroke
				(width 0.1524)
				(type default)
			)
			(layer "F.SilkS")
		)
		(fp_line
			(start 0 4.011168)
			(end -3.330702 -4.771136)
			(stroke
				(width 0.1524)
				(type default)
			)
			(layer "F.SilkS")
		)
		(fp_line
			(start 3.330702 -4.771136)
			(end 0 4.011168)
			(stroke
				(width 0.1524)
				(type default)
			)
			(layer "F.SilkS")
		)
		(fp_line
			(start -3.330702 -4.771136)
			(end 3.330702 -4.771136)
			(stroke
				(width 0.1)
				(type default)
			)
			(layer "F.Fab")
		)
		(fp_line
			(start 0 4.011168)
			(end -3.330702 -4.771136)
			(stroke
				(width 0.1)
				(type default)
			)
			(layer "F.Fab")
		)
		(fp_line
			(start 3.330702 -4.771136)
			(end 0 4.011168)
			(stroke
				(width 0.1)
				(type default)
			)
			(layer "F.Fab")
		)
		(pad "1" thru_hole circle
			(at 0 0)
			(size 2.159 2.159)
			(drill 1.7018)
			(layers "*.Cu" "*.Mask")
			(remove_unused_layers no)
			(net "T1_GND")
			(clearance 0.0254)
			(thermal_gap 0.0254)
		)
		(pad "2" thru_hole circle
			(at -1.27 -3.348736)
			(size 2.159 2.159)
			(drill 1.7018)
			(layers "*.Cu" "*.Mask")
			(remove_unused_layers no)
			(net "TDR_SE_40_OHM_IN1")
			(clearance 0.0254)
			(thermal_gap 0.0254)
		)
		(pad "3" thru_hole circle
			(at 1.27 -3.348736)
			(size 2.159 2.159)
			(drill 1.7018)
			(layers "*.Cu" "*.Mask")
			(remove_unused_layers no)
			(net "TDR_SE_40_OHM_IN1")
			(clearance 0.0254)
			(thermal_gap 0.0254)
		)
	)
	(footprint ""
		(layer "F.Cu")
		(at 103.306372 -363.873034)
		(property "Reference" "R2521"
			(at 0 0 0)
			(layer "F.SilkS")
			(hide yes)
			(effects
				(font
					(size 1.27 1.27)
				)
			)
		)
		(property "Value" ""
			(at 0 0 0)
			(layer "F.Fab")
			(effects
				(font
					(size 1.27 1.27)
				)
			)
		)
		(duplicate_pad_numbers_are_jumpers no)
		(fp_line
			(start -0.7874 -0.4064)
			(end 0.7874 -0.4064)
			(stroke
				(width 0.1524)
				(type default)
			)
			(layer "F.SilkS")
		)
		(fp_line
			(start -0.7874 0.4064)
			(end -0.7874 -0.4064)
			(stroke
				(width 0.1524)
				(type default)
			)
			(layer "F.SilkS")
		)
		(fp_line
			(start 0.7874 -0.4064)
			(end 0.7874 0.4064)
			(stroke
				(width 0.1524)
				(type default)
			)
			(layer "F.SilkS")
		)
		(fp_line
			(start 0.7874 0.4064)
			(end -0.7874 0.4064)
			(stroke
				(width 0.1524)
				(type default)
			)
			(layer "F.SilkS")
		)
		(fp_line
			(start -0.67945 -0.305054)
			(end -0.12065 -0.305054)
			(stroke
				(width 0.1)
				(type default)
			)
			(layer "F.Fab")
		)
		(fp_line
			(start -0.67945 0.3048)
			(end -0.67945 -0.305054)
			(stroke
				(width 0.1)
				(type default)
			)
			(layer "F.Fab")
		)
		(fp_line
			(start -0.12065 -0.305054)
			(end -0.12065 -0.2794)
			(stroke
				(width 0.1)
				(type default)
			)
			(layer "F.Fab")
		)
		(fp_line
			(start -0.12065 -0.2794)
			(end 0.12065 -0.2794)
			(stroke
				(width 0.1)
				(type default)
			)
			(layer "F.Fab")
		)
		(fp_line
			(start -0.12065 0.2794)
			(end -0.12065 0.3048)
			(stroke
				(width 0.1)
				(type default)
			)
			(layer "F.Fab")
		)
		(fp_line
			(start -0.12065 0.3048)
			(end -0.67945 0.3048)
			(stroke
				(width 0.1)
				(type default)
			)
			(layer "F.Fab")
		)
		(fp_line
			(start 0.120396 0.2794)
			(end -0.12065 0.2794)
			(stroke
				(width 0.1)
				(type default)
			)
			(layer "F.Fab")
		)
		(fp_line
			(start 0.120396 0.3048)
			(end 0.120396 0.2794)
			(stroke
				(width 0.1)
				(type default)
			)
			(layer "F.Fab")
		)
		(fp_line
			(start 0.12065 -0.3048)
			(end 0.67945 -0.3048)
			(stroke
				(width 0.1)
				(type default)
			)
			(layer "F.Fab")
		)
		(fp_line
			(start 0.12065 -0.2794)
			(end 0.12065 -0.3048)
			(stroke
				(width 0.1)
				(type default)
			)
			(layer "F.Fab")
		)
		(fp_line
			(start 0.67945 -0.3048)
			(end 0.67945 0.3048)
			(stroke
				(width 0.1)
				(type default)
			)
			(layer "F.Fab")
		)
		(fp_line
			(start 0.67945 0.3048)
			(end 0.120396 0.3048)
			(stroke
				(width 0.1)
				(type default)
			)
			(layer "F.Fab")
		)
		(pad "1" smd circle
			(at -0.40005 0)
			(size 0 0)
			(layers "F.Cu" "F.Mask" "F.Paste")
			(net "SMB_VR_3V3AUX_SDA_R3")
		)
		(pad "2" smd circle
			(at 0.40005 0)
			(size 0 0)
			(layers "F.Cu" "F.Mask" "F.Paste")
			(net "SMB_DIO_PVCCIN_CPU1")
		)
	)
)
